# S9S_MB_2U (Grand Teton) — schematic netlist excerpt (pin names and nets, part order shuffled) for the footprints in the layout excerpt that follows; sources: Cadence DE-HDL packaged netlist, KiCad conversion of 03242023_DA0F0TMBIJ0_F0T_Motherboard_J_brd_V01_OCP.brd

R769  Q_RES  10K 1% CHIP  pkg 0402LF  page 131 : A = PD_TRST_P3 ; B = GND
PD116  SCHOTTKY_AC  B340A-13-F IC  pkg D2010XF  page 242 : A = GND ; C = P12V_SCM_R
R323  Q_RES  0 EMPTY  pkg 1206LF  page 80 : A = PVCCINFAON_CPU0 ; B = PVNN_TERM_CPU0

(kicad_pcb
	(version 20260206)
	(generator "pcbnew")
	(generator_version "10.0")
	(general
		(thickness 1.6)
		(legacy_teardrops no)
	)
	(paper "A4")
	(title_block
		(title "03242023_DA0F0TMBIJ0_F0T_Motherboard_J_brd_V01_OCP.brd")
		(comment 1 "Grand Teton / footprints 2427-2429 of 6105")
	)
	(layers
		(0 "F.Cu" signal "TOP")
		(4 "In1.Cu" signal "GND")
		(6 "In2.Cu" signal "IN1")
		(8 "In3.Cu" signal "GND1")
		(10 "In4.Cu" signal "IN2")
		(12 "In5.Cu" signal "GND2")
		(14 "In6.Cu" signal "IN3")
		(16 "In7.Cu" signal "GND3")
		(18 "In8.Cu" signal "VCC")
		(20 "In9.Cu" signal "VCC1")
		(22 "In10.Cu" signal "GND4")
		(24 "In11.Cu" signal "IN4")
		(26 "In12.Cu" signal "GND5")
		(28 "In13.Cu" signal "IN5")
		(30 "In14.Cu" signal "GND6")
		(32 "In15.Cu" signal "IN6")
		(34 "In16.Cu" signal "GND7")
		(2 "B.Cu" signal "BOTTOM")
		(9 "F.Adhes" user "F.Adhesive")
		(11 "B.Adhes" user "B.Adhesive")
		(13 "F.Paste" user "Package Geometry/Pastemask Top")
		(15 "B.Paste" user "Package Geometry/Pastemask Bottom")
		(5 "F.SilkS" user "Ref Des/Silkscreen Top")
		(7 "B.SilkS" user "Ref Des/Silkscreen Bottom")
		(1 "F.Mask" user "Board Geometry/Soldermask Top")
		(3 "B.Mask" user "Board Geometry/Soldermask Bottom")
		(17 "Dwgs.User" user "User.Drawings")
		(19 "Cmts.User" user "User.Comments")
		(21 "Eco1.User" user "User.Eco1")
		(23 "Eco2.User" user "User.Eco2")
		(25 "Edge.Cuts" user "Board Geometry/Outline")
		(27 "Margin" user)
		(31 "F.CrtYd" user "Package Geometry/Place Bound Top")
		(29 "B.CrtYd" user "Package Geometry/Place Bound Bottom")
		(35 "F.Fab" user "Ref Des/Assembly Top")
		(33 "B.Fab" user "Ref Des/Assembly Bottom")
	)
	(footprint ""
		(layer "F.Cu")
		(at 191.806322 -20.126452 180)
		(property "Reference" "PD116"
			(at 10.696702 -0.955294 0)
			(unlocked yes)
			(layer "F.SilkS")
			(effects
				(font
					(size 0.7874 0.5842)
					(thickness 0.1524)
				)
				(justify left)
			)
		)
		(property "Value" ""
			(at 0 0 180)
			(layer "F.Fab")
			(effects
				(font
					(size 1.27 1.27)
				)
			)
		)
		(duplicate_pad_numbers_are_jumpers no)
		(fp_line
			(start 4.107942 1.459992)
			(end -3.400044 1.459992)
			(stroke
				(width 0.1524)
				(type default)
			)
			(layer "F.SilkS")
		)
		(fp_line
			(start 4.107942 -1.459992)
			(end 4.107942 1.459992)
			(stroke
				(width 0.1524)
				(type default)
			)
			(layer "F.SilkS")
		)
		(fp_line
			(start -3.400044 1.459992)
			(end -3.400044 -1.459992)
			(stroke
				(width 0.1524)
				(type default)
			)
			(layer "F.SilkS")
		)
		(fp_line
			(start -3.400044 -1.459992)
			(end 4.107942 -1.459992)
			(stroke
				(width 0.1524)
				(type default)
			)
			(layer "F.SilkS")
		)
		(fp_rect
			(start 4.107942 -1.459992)
			(end 3.308096 1.459992)
			(stroke
				(width 0)
				(type default)
			)
			(fill yes)
			(layer "F.SilkS")
		)
		(fp_line
			(start 2.29997 1.459992)
			(end -2.29997 1.459992)
			(stroke
				(width 0.1)
				(type default)
			)
			(layer "F.Fab")
		)
		(fp_line
			(start 2.29997 -1.459992)
			(end 2.29997 1.459992)
			(stroke
				(width 0.1)
				(type default)
			)
			(layer "F.Fab")
		)
		(fp_line
			(start -2.29997 1.459992)
			(end -2.29997 -1.459992)
			(stroke
				(width 0.1)
				(type default)
			)
			(layer "F.Fab")
		)
		(fp_line
			(start -2.29997 -1.459992)
			(end 2.29997 -1.459992)
			(stroke
				(width 0.1)
				(type default)
			)
			(layer "F.Fab")
		)
		(fp_text user "-"
			(at 5.4102 0.29845 0)
			(unlocked yes)
			(layer "F.SilkS")
			(effects
				(font
					(size 1.905 1.4224)
					(thickness 0.1524)
				)
				(justify left)
			)
		)
		(fp_text user "+"
			(at -4.7752 -0.12065 180)
			(unlocked yes)
			(layer "F.SilkS")
			(effects
				(font
					(size 1.905 1.4224)
					(thickness 0.1524)
				)
				(justify left)
			)
		)
		(fp_text user "-"
			(at 5.4102 0.29845 0)
			(unlocked yes)
			(layer "F.Fab")
			(effects
				(font
					(size 1.905 1.4224)
					(thickness 0.1524)
				)
				(justify left)
			)
		)
		(fp_text user "+"
			(at -4.7752 -0.12065 180)
			(unlocked yes)
			(layer "F.Fab")
			(effects
				(font
					(size 1.905 1.4224)
					(thickness 0.1524)
				)
				(justify left)
			)
		)
		(pad "A" smd rect
			(at -1.999996 0 270)
			(size 1.7018 2.5146)
			(layers "F.Cu" "F.Mask" "F.Paste")
			(net "GND")
		)
		(pad "C" smd rect
			(at 1.999996 0 270)
			(size 1.7018 2.5146)
			(layers "F.Cu" "F.Mask" "F.Paste")
			(net "P12V_SCM_R")
		)
	)
	(footprint ""
		(layer "F.Cu")
		(at 401.62988 -186.781948)
		(property "Reference" "R323"
			(at 0 0 0)
			(layer "F.SilkS")
			(hide yes)
			(effects
				(font
					(size 1.27 1.27)
				)
			)
		)
		(property "Value" ""
			(at 0 0 0)
			(layer "F.Fab")
			(effects
				(font
					(size 1.27 1.27)
				)
			)
		)
		(duplicate_pad_numbers_are_jumpers no)
		(fp_line
			(start -2.044192 -0.94361)
			(end -2.044192 0.898398)
			(stroke
				(width 0.1524)
				(type default)
			)
			(layer "F.SilkS")
		)
		(fp_line
			(start -2.044192 0.94361)
			(end 2.044192 0.94361)
			(stroke
				(width 0.1524)
				(type default)
			)
			(layer "F.SilkS")
		)
		(fp_line
			(start 2.044192 -0.94361)
			(end -2.044192 -0.94361)
			(stroke
				(width 0.1524)
				(type default)
			)
			(layer "F.SilkS")
		)
		(fp_line
			(start 2.044192 0.94361)
			(end 2.044192 -0.94361)
			(stroke
				(width 0.1524)
				(type default)
			)
			(layer "F.SilkS")
		)
		(fp_line
			(start -1.625092 -0.87503)
			(end -1.625092 0.87503)
			(stroke
				(width 0.1)
				(type default)
			)
			(layer "F.Fab")
		)
		(fp_line
			(start -1.625092 0.87503)
			(end 1.625092 0.87503)
			(stroke
				(width 0.1)
				(type default)
			)
			(layer "F.Fab")
		)
		(fp_line
			(start 1.625092 -0.87503)
			(end -1.625092 -0.87503)
			(stroke
				(width 0.1)
				(type default)
			)
			(layer "F.Fab")
		)
		(fp_line
			(start 1.625092 0.87503)
			(end 1.625092 -0.87503)
			(stroke
				(width 0.1)
				(type default)
			)
			(layer "F.Fab")
		)
		(pad "1" smd rect
			(at -1.450086 0)
			(size 0.9144 1.6002)
			(layers "F.Cu" "F.Mask" "F.Paste")
			(net "PVCCINFAON_CPU0")
		)
		(pad "2" smd rect
			(at 1.450086 0)
			(size 0.9144 1.6002)
			(layers "F.Cu" "F.Mask" "F.Paste")
			(net "PVNN_TERM_CPU0")
		)
	)
	(footprint ""
		(layer "F.Cu")
		(at 403.946106 -62.994032)
		(property "Reference" "R769"
			(at 0 0 0)
			(layer "F.SilkS")
			(hide yes)
			(effects
				(font
					(size 1.27 1.27)
				)
			)
		)
		(property "Value" ""
			(at 0 0 0)
			(layer "F.Fab")
			(effects
				(font
					(size 1.27 1.27)
				)
			)
		)
		(duplicate_pad_numbers_are_jumpers no)
		(fp_line
			(start -0.7874 -0.4064)
			(end 0.7874 -0.4064)
			(stroke
				(width 0.1524)
				(type default)
			)
			(layer "F.SilkS")
		)
		(fp_line
			(start -0.7874 0.4064)
			(end -0.7874 -0.4064)
			(stroke
				(width 0.1524)
				(type default)
			)
			(layer "F.SilkS")
		)
		(fp_line
			(start 0.7874 -0.4064)
			(end 0.7874 0.4064)
			(stroke
				(width 0.1524)
				(type default)
			)
			(layer "F.SilkS")
		)
		(fp_line
			(start 0.7874 0.4064)
			(end -0.7874 0.4064)
			(stroke
				(width 0.1524)
				(type default)
			)
			(layer "F.SilkS")
		)
		(fp_line
			(start -0.67945 -0.305054)
			(end -0.12065 -0.305054)
			(stroke
				(width 0.1)
				(type default)
			)
			(layer "F.Fab")
		)
		(fp_line
			(start -0.67945 0.3048)
			(end -0.67945 -0.305054)
			(stroke
				(width 0.1)
				(type default)
			)
			(layer "F.Fab")
		)
		(fp_line
			(start -0.12065 -0.305054)
			(end -0.12065 -0.2794)
			(stroke
				(width 0.1)
				(type default)
			)
			(layer "F.Fab")
		)
		(fp_line
			(start -0.12065 -0.2794)
			(end 0.12065 -0.2794)
			(stroke
				(width 0.1)
				(type default)
			)
			(layer "F.Fab")
		)
		(fp_line
			(start -0.12065 0.2794)
			(end -0.12065 0.3048)
			(stroke
				(width 0.1)
				(type default)
			)
			(layer "F.Fab")
		)
		(fp_line
			(start -0.12065 0.3048)
			(end -0.67945 0.3048)
			(stroke
				(width 0.1)
				(type default)
			)
			(layer "F.Fab")
		)
		(fp_line
			(start 0.120396 0.2794)
			(end -0.12065 0.2794)
			(stroke
				(width 0.1)
				(type default)
			)
			(layer "F.Fab")
		)
		(fp_line
			(start 0.120396 0.3048)
			(end 0.120396 0.2794)
			(stroke
				(width 0.1)
				(type default)
			)
			(layer "F.Fab")
		)
		(fp_line
			(start 0.12065 -0.3048)
			(end 0.67945 -0.3048)
			(stroke
				(width 0.1)
				(type default)
			)
			(layer "F.Fab")
		)
		(fp_line
			(start 0.12065 -0.2794)
			(end 0.12065 -0.3048)
			(stroke
				(width 0.1)
				(type default)
			)
			(layer "F.Fab")
		)
		(fp_line
			(start 0.67945 -0.3048)
			(end 0.67945 0.3048)
			(stroke
				(width 0.1)
				(type default)
			)
			(layer "F.Fab")
		)
		(fp_line
			(start 0.67945 0.3048)
			(end 0.120396 0.3048)
			(stroke
				(width 0.1)
				(type default)
			)
			(layer "F.Fab")
		)
		(pad "1" smd circle
			(at -0.40005 0)
			(size 0 0)
			(layers "F.Cu" "F.Mask" "F.Paste")
			(net "PD_TRST_P3")
		)
		(pad "2" smd circle
			(at 0.40005 0)
			(size 0 0)
			(layers "F.Cu" "F.Mask" "F.Paste")
			(net "GND")
		)
	)
)
